(kicad_pcb
	(version 20241229)
	(generator "pcbnew")
	(generator_version "9.0")
	(general
		(thickness 1.6296)
		(legacy_teardrops no)
	)
	(paper "A3")
	(title_block
		(title "Thunderbolt to 10GbE adapter")
		(date "2026-04-21")
		(rev "1.1.0")
		(company "Antmicro Ltd")
		(comment 1 "www.antmicro.com")
		(comment 9 "footprints 690-694 of 703")
	)
	(layers
		(0 "F.Cu" signal)
		(4 "In1.Cu" signal)
		(6 "In2.Cu" signal)
		(8 "In3.Cu" signal)
		(10 "In4.Cu" signal)
		(12 "In5.Cu" signal)
		(14 "In6.Cu" signal)
		(2 "B.Cu" signal)
		(9 "F.Adhes" user "F.Adhesive")
		(11 "B.Adhes" user "B.Adhesive")
		(13 "F.Paste" user)
		(15 "B.Paste" user)
		(5 "F.SilkS" user "F.Silkscreen")
		(7 "B.SilkS" user "B.Silkscreen")
		(1 "F.Mask" user)
		(3 "B.Mask" user)
		(17 "Dwgs.User" user "User.Drawings")
		(19 "Cmts.User" user "User.Comments")
		(21 "Eco1.User" user "User.Eco1")
		(23 "Eco2.User" user "User.Eco2")
		(25 "Edge.Cuts" user)
		(27 "Margin" user)
		(31 "F.CrtYd" user "F.Courtyard")
		(29 "B.CrtYd" user "B.Courtyard")
		(35 "F.Fab" user)
		(33 "B.Fab" user)
	)
	(footprint "antmicro-footprints:R_0402_1005Metric"
		(layer "B.Cu")
		(at 162.381866 75.485118)
		(descr "Resistor SMD 0402")
		(tags "resistor SMD 0402")
		(property "Reference" "R175"
			(at 2.368134 0.014883 180)
			(layer "B.SilkS")
			(effects
				(font
					(size 0.7 0.7)
					(thickness 0.15)
				)
				(justify mirror)
			)
		)
		(property "Value" "R_1k_0402"
			(at -1.011843 -1.772047 180)
			(layer "B.Fab")
			(effects
				(font
					(size 0.7 0.7)
					(thickness 0.15)
				)
				(justify left bottom mirror)
			)
		)
		(property "Datasheet" "https://www.bourns.com/docs/product-datasheets/cr.pdf"
			(at 0 0 180)
			(layer "B.Fab")
			(hide yes)
			(effects
				(font
					(size 1.27 1.27)
					(thickness 0.15)
				)
				(justify mirror)
			)
		)
		(property "Description" "SMD Chip Resistor, 1 kohm, ± 1%, 63 mW, 0402 [1005 Metric], Thick Film, General Purpose"
			(at 0 0 180)
			(layer "B.Fab")
			(hide yes)
			(effects
				(font
					(size 1.27 1.27)
					(thickness 0.15)
				)
				(justify mirror)
			)
		)
		(property "MPN" "CR0402-FX-1001GLF"
			(at 0 0 0)
			(unlocked yes)
			(layer "B.Fab")
			(hide yes)
			(effects
				(font
					(size 1 1)
					(thickness 0.15)
				)
				(justify mirror)
			)
		)
		(property "Manufacturer" "Bourns"
			(at 0 0 0)
			(unlocked yes)
			(layer "B.Fab")
			(hide yes)
			(effects
				(font
					(size 1 1)
					(thickness 0.15)
				)
				(justify mirror)
			)
		)
		(property "License" "Apache-2.0"
			(at 0 0 0)
			(unlocked yes)
			(layer "B.Fab")
			(hide yes)
			(effects
				(font
					(size 1 1)
					(thickness 0.15)
				)
				(justify mirror)
			)
		)
		(property "Author" "Antmicro"
			(at 0 0 0)
			(unlocked yes)
			(layer "B.Fab")
			(hide yes)
			(effects
				(font
					(size 1 1)
					(thickness 0.15)
				)
				(justify mirror)
			)
		)
		(property "Val" "1k"
			(at 0 0 0)
			(unlocked yes)
			(layer "B.Fab")
			(hide yes)
			(effects
				(font
					(size 1 1)
					(thickness 0.15)
				)
				(justify mirror)
			)
		)
		(property "Tolerance" "1%"
			(at 0 0 0)
			(unlocked yes)
			(layer "B.Fab")
			(hide yes)
			(effects
				(font
					(size 1 1)
					(thickness 0.15)
				)
				(justify mirror)
			)
		)
		(sheetname "/X710-AT2 Misc/")
		(sheetfile "x710-at2-mics.kicad_sch")
		(attr smd)
		(fp_rect
			(start -0.925 0.47)
			(end 0.925 -0.47)
			(stroke
				(width 0.05)
				(type default)
			)
			(fill no)
			(layer "B.CrtYd")
		)
		(fp_rect
			(start -0.5 0.25)
			(end 0.5 -0.25)
			(stroke
				(width 0.15)
				(type solid)
			)
			(fill no)
			(layer "B.Fab")
		)
		(fp_text user "${REFERENCE}"
			(at -0.95 -3.168 180)
			(layer "B.Fab")
			(effects
				(font
					(size 0.7 0.7)
					(thickness 0.15)
				)
				(justify left bottom mirror)
			)
		)
		(fp_text user "License: Apache-2.0"
			(at -0.95 -5.169 180)
			(layer "B.Fab")
			(effects
				(font
					(size 0.7 0.7)
					(thickness 0.15)
				)
				(justify left bottom mirror)
			)
		)
		(fp_text user "Author: Antmicro"
			(at -0.95 -4.169 180)
			(layer "B.Fab")
			(effects
				(font
					(size 0.7 0.7)
					(thickness 0.15)
				)
				(justify left bottom mirror)
			)
		)
		(pad "1" smd roundrect
			(at -0.48 0)
			(size 0.59 0.64)
			(layers "B.Cu" "B.Mask" "B.Paste")
			(roundrect_rratio 0.25)
			(net 111 "/X710-AT2 10GbE/~{P0_INT}")
			(pintype "passive")
		)
		(pad "2" smd roundrect
			(at 0.48 0)
			(size 0.59 0.64)
			(layers "B.Cu" "B.Mask" "B.Paste")
			(roundrect_rratio 0.25)
			(net 7 "+3V3")
			(pintype "passive")
		)
	)
	(footprint "antmicro-footprints:D_SOD-323F"
		(layer "B.Cu")
		(at 116.2 109.6 -90)
		(property "Reference" "D3"
			(at -0.8 -2 90)
			(layer "B.SilkS")
			(effects
				(font
					(size 0.7 0.7)
					(thickness 0.15)
				)
				(justify left bottom mirror)
			)
		)
		(property "Value" "MM3Z3V3C"
			(at 0 -1.9 90)
			(layer "B.Fab")
			(effects
				(font
					(size 0.7 0.7)
					(thickness 0.15)
				)
				(justify left bottom mirror)
			)
		)
		(property "Datasheet" "https://www.onsemi.com/download/data-sheet/pdf/mm3z9v1c-d.pdf"
			(at 0 0 90)
			(layer "B.Fab")
			(hide yes)
			(effects
				(font
					(size 1.27 1.27)
					(thickness 0.15)
				)
				(justify mirror)
			)
		)
		(property "Description" "Zener Single Diode, 3.3 V, 200 mW, SOD-323F, 2 Pins, 150 °C, Surface Mount"
			(at 0 0 90)
			(layer "B.Fab")
			(hide yes)
			(effects
				(font
					(size 1.27 1.27)
					(thickness 0.15)
				)
				(justify mirror)
			)
		)
		(property "MPN" "MM3Z3V3C"
			(at 0 0 270)
			(unlocked yes)
			(layer "B.Fab")
			(hide yes)
			(effects
				(font
					(size 1 1)
					(thickness 0.15)
				)
				(justify mirror)
			)
		)
		(property "Manufacturer" "ON Semiconductor"
			(at 0 0 270)
			(unlocked yes)
			(layer "B.Fab")
			(hide yes)
			(effects
				(font
					(size 1 1)
					(thickness 0.15)
				)
				(justify mirror)
			)
		)
		(property "License" "Apache-2.0"
			(at 0 0 270)
			(unlocked yes)
			(layer "B.Fab")
			(hide yes)
			(effects
				(font
					(size 1 1)
					(thickness 0.15)
				)
				(justify mirror)
			)
		)
		(property "Author" "Antmicro"
			(at 0 0 270)
			(unlocked yes)
			(layer "B.Fab")
			(hide yes)
			(effects
				(font
					(size 1 1)
					(thickness 0.15)
				)
				(justify mirror)
			)
		)
		(sheetname "/PD and TB DC-DC/")
		(sheetfile "PD_and_TB_DC_DC.kicad_sch")
		(attr smd)
		(fp_line
			(start -0.975 0.749)
			(end -0.975 0.449)
			(stroke
				(width 0.15)
				(type solid)
			)
			(layer "B.SilkS")
		)
		(fp_line
			(start -0.625 0.749)
			(end -0.975 0.749)
			(stroke
				(width 0.15)
				(type solid)
			)
			(layer "B.SilkS")
		)
		(fp_line
			(start 0.623 0.749)
			(end 0.973 0.749)
			(stroke
				(width 0.15)
				(type solid)
			)
			(layer "B.SilkS")
		)
		(fp_line
			(start 0.973 0.749)
			(end 0.973 0.449)
			(stroke
				(width 0.15)
				(type solid)
			)
			(layer "B.SilkS")
		)
		(fp_line
			(start -0.5 0.425)
			(end -0.5 -0.425)
			(stroke
				(width 0.15)
				(type solid)
			)
			(layer "B.SilkS")
		)
		(fp_line
			(start 0.973 -0.451)
			(end 0.973 -0.749)
			(stroke
				(width 0.15)
				(type solid)
			)
			(layer "B.SilkS")
		)
		(fp_line
			(start -0.975 -0.749)
			(end -0.975 -0.451)
			(stroke
				(width 0.15)
				(type solid)
			)
			(layer "B.SilkS")
		)
		(fp_line
			(start -0.625 -0.749)
			(end -0.975 -0.749)
			(stroke
				(width 0.15)
				(type solid)
			)
			(layer "B.SilkS")
		)
		(fp_line
			(start 0.973 -0.749)
			(end 0.623 -0.749)
			(stroke
				(width 0.15)
				(type solid)
			)
			(layer "B.SilkS")
		)
		(fp_rect
			(start -1.55 0.95)
			(end 1.55 -0.95)
			(stroke
				(width 0.05)
				(type solid)
			)
			(fill no)
			(layer "B.CrtYd")
		)
		(fp_rect
			(start -1.25 0.676)
			(end 1.245365 -0.676)
			(stroke
				(width 0.1)
				(type solid)
			)
			(fill no)
			(layer "B.Fab")
		)
		(fp_text user "License: Apache-2.0"
			(at -1.7 -6.299 90)
			(layer "B.Fab")
			(effects
				(font
					(size 0.7 0.7)
					(thickness 0.15)
				)
				(justify left bottom mirror)
			)
		)
		(fp_text user "${REFERENCE}"
			(at -1.7 -5.099 90)
			(layer "B.Fab")
			(effects
				(font
					(size 0.7 0.7)
					(thickness 0.15)
				)
				(justify left bottom mirror)
			)
		)
		(fp_text user "Author: Antmicro"
			(at -1.7 -3.899 90)
			(layer "B.Fab")
			(effects
				(font
					(size 0.7 0.7)
					(thickness 0.15)
				)
				(justify left bottom mirror)
			)
		)
		(pad "1" smd roundrect
			(at -1.051 -0.001 270)
			(size 0.8 0.6)
			(layers "B.Cu" "B.Mask" "B.Paste")
			(roundrect_rratio 0.15)
			(net 413 "Net-(D3-C)")
			(pinfunction "C")
			(pintype "passive")
		)
		(pad "2" smd roundrect
			(at 1.05 -0.001 270)
			(size 0.8 0.6)
			(layers "B.Cu" "B.Mask" "B.Paste")
			(roundrect_rratio 0.15)
			(net 23 "GND")
			(pinfunction "A")
			(pintype "passive")
		)
	)
	(footprint "antmicro-footprints:C_0402_1005Metric"
		(layer "B.Cu")
		(at 157.681866 93.385117 -90)
		(descr "Capacitor SMD 0402")
		(tags "capacitor SMD 0402")
		(property "Reference" "C160"
			(at 9.914883 -18.068134 90)
			(layer "B.SilkS")
			(effects
				(font
					(size 0.7 0.7)
					(thickness 0.15)
				)
				(justify mirror)
			)
		)
		(property "Value" "C_100n_0402"
			(at -1.022927 -2.155213 90)
			(layer "B.Fab")
			(effects
				(font
					(size 0.7 0.7)
					(thickness 0.15)
				)
				(justify left bottom mirror)
			)
		)
		(property "Datasheet" "https://www.murata.com/products/productdetail?partno=GRM155R61H104KE14%23"
			(at 0 0 90)
			(layer "B.Fab")
			(hide yes)
			(effects
				(font
					(size 1.27 1.27)
					(thickness 0.15)
				)
				(justify mirror)
			)
		)
		(property "Description" "SMD Multilayer Ceramic Capacitor, 0.1 µF, 50 V, 0402 [1005 Metric], ± 10%, X5R, GRM Series"
			(at 0 0 90)
			(layer "B.Fab")
			(hide yes)
			(effects
				(font
					(size 1.27 1.27)
					(thickness 0.15)
				)
				(justify mirror)
			)
		)
		(property "MPN" "GRM155R61H104KE14D"
			(at 0 0 270)
			(unlocked yes)
			(layer "B.Fab")
			(hide yes)
			(effects
				(font
					(size 1 1)
					(thickness 0.15)
				)
				(justify mirror)
			)
		)
		(property "Val" "100n"
			(at 0 0 270)
			(unlocked yes)
			(layer "B.Fab")
			(hide yes)
			(effects
				(font
					(size 1 1)
					(thickness 0.15)
				)
				(justify mirror)
			)
		)
		(property "Voltage" "50V"
			(at 0 0 270)
			(unlocked yes)
			(layer "B.Fab")
			(hide yes)
			(effects
				(font
					(size 1 1)
					(thickness 0.15)
				)
				(justify mirror)
			)
		)
		(property "Dielectric" "X5R"
			(at 0 0 270)
			(unlocked yes)
			(layer "B.Fab")
			(hide yes)
			(effects
				(font
					(size 1 1)
					(thickness 0.15)
				)
				(justify mirror)
			)
		)
		(property "Manufacturer" "Murata"
			(at 0 0 270)
			(unlocked yes)
			(layer "B.Fab")
			(hide yes)
			(effects
				(font
					(size 1 1)
					(thickness 0.15)
				)
				(justify mirror)
			)
		)
		(property "License" "Apache-2.0"
			(at 0 0 270)
			(unlocked yes)
			(layer "B.Fab")
			(hide yes)
			(effects
				(font
					(size 1 1)
					(thickness 0.15)
				)
				(justify mirror)
			)
		)
		(property "Author" "Antmicro"
			(at 0 0 270)
			(unlocked yes)
			(layer "B.Fab")
			(hide yes)
			(effects
				(font
					(size 1 1)
					(thickness 0.15)
				)
				(justify mirror)
			)
		)
		(sheetname "/X710-AT2 power/")
		(sheetfile "x710-at2-power.kicad_sch")
		(attr smd)
		(fp_rect
			(start -0.925 0.47)
			(end 0.925 -0.47)
			(stroke
				(width 0.05)
				(type default)
			)
			(fill no)
			(layer "B.CrtYd")
		)
		(fp_line
			(start -0.494 0.25)
			(end 0.504 0.25)
			(stroke
				(width 0.15)
				(type solid)
			)
			(layer "B.Fab")
		)
		(fp_line
			(start 0.504 0.25)
			(end 0.504 -0.248)
			(stroke
				(width 0.15)
				(type solid)
			)
			(layer "B.Fab")
		)
		(fp_line
			(start -0.494 -0.248)
			(end -0.494 0.25)
			(stroke
				(width 0.15)
				(type solid)
			)
			(layer "B.Fab")
		)
		(fp_line
			(start 0.504 -0.248)
			(end -0.494 -0.248)
			(stroke
				(width 0.15)
				(type solid)
			)
			(layer "B.Fab")
		)
		(fp_text user "License: Apache-2.0"
			(at -0.939 -5.799 90)
			(layer "B.Fab")
			(effects
				(font
					(size 0.7 0.7)
					(thickness 0.15)
				)
				(justify left bottom mirror)
			)
		)
		(fp_text user "Author: Antmicro"
			(at -0.939 -3.399 90)
			(layer "B.Fab")
			(effects
				(font
					(size 0.7 0.7)
					(thickness 0.15)
				)
				(justify left bottom mirror)
			)
		)
		(fp_text user "${REFERENCE}"
			(at -0.939 -4.599 90)
			(layer "B.Fab")
			(effects
				(font
					(size 0.7 0.7)
					(thickness 0.15)
				)
				(justify left bottom mirror)
			)
		)
		(pad "1" smd roundrect
			(at -0.48 0 270)
			(size 0.59 0.64)
			(layers "B.Cu" "B.Mask" "B.Paste")
			(roundrect_rratio 0.25)
			(net 23 "GND")
			(pintype "passive")
		)
		(pad "2" smd roundrect
			(at 0.48 0 270)
			(size 0.59 0.64)
			(layers "B.Cu" "B.Mask" "B.Paste")
			(roundrect_rratio 0.25)
			(net 136 "+1V0")
			(pintype "passive")
		)
	)
	(footprint "antmicro-footprints:C_0402_1005Metric"
		(layer "B.Cu")
		(at 126.25 134.75 90)
		(descr "Capacitor SMD 0402")
		(tags "capacitor SMD 0402")
		(property "Reference" "C37"
			(at -1.25 0.5 270)
			(layer "B.SilkS")
			(effects
				(font
					(size 0.7 0.7)
					(thickness 0.15)
				)
				(justify left bottom mirror)
			)
		)
		(property "Value" "C_220n_0402"
			(at -1.022927 -2.155213 270)
			(layer "B.Fab")
			(effects
				(font
					(size 0.7 0.7)
					(thickness 0.15)
				)
				(justify left bottom mirror)
			)
		)
		(property "Datasheet" "https://www.yageo.com/en/Chart/Download/pdf/CC0402KRX5R6BB224"
			(at 0 0 270)
			(layer "B.Fab")
			(hide yes)
			(effects
				(font
					(size 1.27 1.27)
					(thickness 0.15)
				)
				(justify mirror)
			)
		)
		(property "Description" "SMD Multilayer Ceramic Capacitor, 0.22 µF, 10 V, 0402 [1005 Metric], ± 10%, X5R, CC Series"
			(at 0 0 270)
			(layer "B.Fab")
			(hide yes)
			(effects
				(font
					(size 1.27 1.27)
					(thickness 0.15)
				)
				(justify mirror)
			)
		)
		(property "MPN" "CC0402KRX5R6BB224"
			(at 0 0 90)
			(unlocked yes)
			(layer "B.Fab")
			(hide yes)
			(effects
				(font
					(size 1 1)
					(thickness 0.15)
				)
				(justify mirror)
			)
		)
		(property "Manufacturer" "YAGEO"
			(at 0 0 90)
			(unlocked yes)
			(layer "B.Fab")
			(hide yes)
			(effects
				(font
					(size 1 1)
					(thickness 0.15)
				)
				(justify mirror)
			)
		)
		(property "License" "Apache-2.0"
			(at 0 0 90)
			(unlocked yes)
			(layer "B.Fab")
			(hide yes)
			(effects
				(font
					(size 1 1)
					(thickness 0.15)
				)
				(justify mirror)
			)
		)
		(property "Val" "220n"
			(at 0 0 90)
			(unlocked yes)
			(layer "B.Fab")
			(hide yes)
			(effects
				(font
					(size 1 1)
					(thickness 0.15)
				)
				(justify mirror)
			)
		)
		(property "Voltage" ""
			(at 0 0 90)
			(unlocked yes)
			(layer "B.Fab")
			(hide yes)
			(effects
				(font
					(size 1 1)
					(thickness 0.15)
				)
				(justify mirror)
			)
		)
		(property "Dielectric" ""
			(at 0 0 90)
			(unlocked yes)
			(layer "B.Fab")
			(hide yes)
			(effects
				(font
					(size 1 1)
					(thickness 0.15)
				)
				(justify mirror)
			)
		)
		(property "Author" "Antmicro"
			(at 0 0 90)
			(unlocked yes)
			(layer "B.Fab")
			(hide yes)
			(effects
				(font
					(size 1 1)
					(thickness 0.15)
				)
				(justify mirror)
			)
		)
		(sheetname "/TB Controller/")
		(sheetfile "tb.kicad_sch")
		(attr smd)
		(fp_rect
			(start -0.925 0.47)
			(end 0.925 -0.47)
			(stroke
				(width 0.05)
				(type default)
			)
			(fill no)
			(layer "B.CrtYd")
		)
		(fp_line
			(start 0.504 -0.248)
			(end -0.494 -0.248)
			(stroke
				(width 0.15)
				(type solid)
			)
			(layer "B.Fab")
		)
		(fp_line
			(start -0.494 -0.248)
			(end -0.494 0.25)
			(stroke
				(width 0.15)
				(type solid)
			)
			(layer "B.Fab")
		)
		(fp_line
			(start 0.504 0.25)
			(end 0.504 -0.248)
			(stroke
				(width 0.15)
				(type solid)
			)
			(layer "B.Fab")
		)
		(fp_line
			(start -0.494 0.25)
			(end 0.504 0.25)
			(stroke
				(width 0.15)
				(type solid)
			)
			(layer "B.Fab")
		)
		(fp_text user "Author: Antmicro"
			(at -0.939 -3.399 270)
			(layer "B.Fab")
			(effects
				(font
					(size 0.7 0.7)
					(thickness 0.15)
				)
				(justify left bottom mirror)
			)
		)
		(fp_text user "License: Apache-2.0"
			(at -0.939 -5.799 270)
			(layer "B.Fab")
			(effects
				(font
					(size 0.7 0.7)
					(thickness 0.15)
				)
				(justify left bottom mirror)
			)
		)
		(fp_text user "${REFERENCE}"
			(at -0.939 -4.599 270)
			(layer "B.Fab")
			(effects
				(font
					(size 0.7 0.7)
					(thickness 0.15)
				)
				(justify left bottom mirror)
			)
		)
		(pad "1" smd roundrect
			(at -0.48 0 90)
			(size 0.59 0.64)
			(layers "B.Cu" "B.Mask" "B.Paste")
			(roundrect_rratio 0.25)
			(net 312 "/PD and TB DC-DC/USB3.TX1_N")
			(pintype "passive")
		)
		(pad "2" smd roundrect
			(at 0.48 0 90)
			(size 0.59 0.64)
			(layers "B.Cu" "B.Mask" "B.Paste")
			(roundrect_rratio 0.25)
			(net 174 "/TB Controller/PA_TX1_N")
			(pintype "passive")
		)
	)
	(footprint "antmicro-footprints:TP_SMD_0.75mm"
		(layer "B.Cu")
		(at 155.231866 62.935117 180)
		(property "Reference" "TP21"
			(at -0.368134 3.135117 270)
			(layer "B.SilkS")
			(effects
				(font
					(size 0.7 0.7)
					(thickness 0.15)
				)
				(justify left bottom mirror)
			)
		)
		(property "Value" "TP_0.75mm_SMD"
			(at 0 -1.2 0)
			(layer "B.Fab")
			(effects
				(font
					(size 0.7 0.7)
					(thickness 0.15)
				)
				(justify left bottom mirror)
			)
		)
		(property "Description" "SMT test point"
			(at 0 0 0)
			(layer "B.Fab")
			(hide yes)
			(effects
				(font
					(size 1.27 1.27)
					(thickness 0.15)
				)
				(justify mirror)
			)
		)
		(property "MPN" ""
			(at 0 0 180)
			(unlocked yes)
			(layer "B.Fab")
			(hide yes)
			(effects
				(font
					(size 1 1)
					(thickness 0.15)
				)
				(justify mirror)
			)
		)
		(property "Manufacturer" ""
			(at 0 0 180)
			(unlocked yes)
			(layer "B.Fab")
			(hide yes)
			(effects
				(font
					(size 1 1)
					(thickness 0.15)
				)
				(justify mirror)
			)
		)
		(property "Author" "Antmicro"
			(at 0 0 180)
			(unlocked yes)
			(layer "B.Fab")
			(hide yes)
			(effects
				(font
					(size 1 1)
					(thickness 0.15)
				)
				(justify mirror)
			)
		)
		(property "License" "Apache-2.0"
			(at 0 0 180)
			(unlocked yes)
			(layer "B.Fab")
			(hide yes)
			(effects
				(font
					(size 1 1)
					(thickness 0.15)
				)
				(justify mirror)
			)
		)
		(sheetname "/X710-AT2 Misc/")
		(sheetfile "x710-at2-mics.kicad_sch")
		(attr exclude_from_pos_files exclude_from_bom)
		(fp_circle
			(center 0 0)
			(end 0.475 0)
			(stroke
				(width 0.05)
				(type default)
			)
			(fill no)
			(layer "B.CrtYd")
		)
		(fp_text user "License: Apache-2.0"
			(at -0.4 -5.101 0)
			(layer "B.Fab")
			(effects
				(font
					(size 0.7 0.7)
					(thickness 0.15)
				)
				(justify left bottom mirror)
			)
		)
		(fp_text user "${REFERENCE}"
			(at -0.4 -2.7 0)
			(layer "B.Fab")
			(effects
				(font
					(size 0.7 0.7)
					(thickness 0.15)
				)
				(justify left bottom mirror)
			)
		)
		(fp_text user "Author: Antmicro"
			(at -0.4 -3.901 0)
			(layer "B.Fab")
			(effects
				(font
					(size 0.7 0.7)
					(thickness 0.15)
				)
				(justify left bottom mirror)
			)
		)
		(pad "1" smd circle
			(at 0 0 180)
			(size 0.75 0.75)
			(layers "B.Cu" "B.Mask")
			(net 145 "/X710-AT2 Misc/NCSI.ARB_IN")
			(pinfunction "1")
			(pintype "passive")
		)
	)
)
